(kicad_pcb
	(version 20241229)
	(generator "pcbnew")
	(generator_version "9.0")
	(general
		(thickness 1.292)
		(legacy_teardrops no)
	)
	(paper "A4")
	(title_block
		(title "LPDDR5 Testbed")
		(date "2023-12-19")
		(rev "1.0.0")
		(comment 9 "footprints 13-15 of 160")
	)
	(layers
		(0 "F.Cu" signal)
		(4 "In1.Cu" power)
		(6 "In2.Cu" power)
		(8 "In3.Cu" signal)
		(10 "In4.Cu" signal)
		(2 "B.Cu" signal)
		(9 "F.Adhes" user "F.Adhesive")
		(11 "B.Adhes" user "B.Adhesive")
		(13 "F.Paste" user)
		(15 "B.Paste" user)
		(5 "F.SilkS" user "F.Silkscreen")
		(7 "B.SilkS" user "B.Silkscreen")
		(1 "F.Mask" user)
		(3 "B.Mask" user)
		(17 "Dwgs.User" user "User.Drawings")
		(19 "Cmts.User" user "User.Comments")
		(21 "Eco1.User" user "User.Eco1")
		(23 "Eco2.User" user "User.Eco2")
		(25 "Edge.Cuts" user)
		(27 "Margin" user)
		(31 "F.CrtYd" user "F.Courtyard")
		(29 "B.CrtYd" user "B.Courtyard")
		(35 "F.Fab" user)
		(33 "B.Fab" user)
	)
	(footprint "antmicro-footprints:R_0402_1005Metric"
		(layer "F.Cu")
		(at 136.65 93.85 90)
		(descr "Resistor SMD 0402")
		(tags "resistor SMD 0402")
		(property "Reference" "R70"
			(at -1.122484 -0.772697 90)
			(unlocked yes)
			(layer "F.SilkS")
			(effects
				(font
					(size 0.7 0.7)
					(thickness 0.15)
				)
				(justify left bottom)
			)
		)
		(property "Value" "R_100R_0402"
			(at -1.011843 1.772047 90)
			(layer "F.Fab")
			(effects
				(font
					(size 0.7 0.7)
					(thickness 0.15)
				)
				(justify left bottom)
			)
		)
		(property "Author" "Antmicro"
			(at 230.5 -42.8 0)
			(layer "F.Fab")
			(hide yes)
			(effects
				(font
					(size 1 1)
					(thickness 0.15)
				)
			)
		)
		(property "License" "Apache-2.0"
			(at 230.5 -42.8 0)
			(layer "F.Fab")
			(hide yes)
			(effects
				(font
					(size 1 1)
					(thickness 0.15)
				)
			)
		)
		(property "MPN" "CR0402-FX-1000GLF"
			(at 230.5 -42.8 0)
			(layer "F.Fab")
			(hide yes)
			(effects
				(font
					(size 1 1)
					(thickness 0.15)
				)
			)
		)
		(property "Manufacturer" "Bourns"
			(at 230.5 -42.8 0)
			(layer "F.Fab")
			(hide yes)
			(effects
				(font
					(size 1 1)
					(thickness 0.15)
				)
			)
		)
		(property "Tolerance" "1%"
			(at 230.5 -42.8 0)
			(layer "F.Fab")
			(hide yes)
			(effects
				(font
					(size 1 1)
					(thickness 0.15)
				)
			)
		)
		(property "Val" "100R"
			(at 230.5 -42.8 0)
			(layer "F.Fab")
			(hide yes)
			(effects
				(font
					(size 1 1)
					(thickness 0.15)
				)
			)
		)
		(sheetname "Translators1")
		(sheetfile "translators.kicad_sch")
		(attr smd)
		(fp_rect
			(start -0.93 -0.47)
			(end 0.93 0.47)
			(stroke
				(width 0.05)
				(type solid)
			)
			(fill no)
			(layer "F.CrtYd")
		)
		(fp_rect
			(start -0.5 -0.25)
			(end 0.5 0.25)
			(stroke
				(width 0.15)
				(type solid)
			)
			(fill no)
			(layer "F.Fab")
		)
		(pad "1" smd roundrect
			(at -0.485 0 90)
			(size 0.59 0.64)
			(layers "F.Cu" "F.Mask" "F.Paste")
			(roundrect_rratio 0.25)
			(net 154 "/SODIMM/LPDDR5_IN_B.CK_P")
			(pintype "passive")
		)
		(pad "2" smd roundrect
			(at 0.485 0 90)
			(size 0.59 0.64)
			(layers "F.Cu" "F.Mask" "F.Paste")
			(roundrect_rratio 0.25)
			(net 112 "/LPDDR5/LPDDR5_B.CK_P")
			(pintype "passive")
		)
	)
	(footprint "antmicro-footprints:C_0402_1005Metric"
		(layer "F.Cu")
		(at 164.475 71.65 180)
		(descr "Capacitor SMD 0402")
		(tags "capacitor SMD 0402")
		(property "Reference" "C21"
			(at -1.125 -2.65 0)
			(unlocked yes)
			(layer "F.SilkS")
			(effects
				(font
					(size 0.7 0.7)
					(thickness 0.15)
				)
				(justify right bottom)
			)
		)
		(property "Value" "C_4u7_0402"
			(at -1.022927 2.155213 0)
			(layer "F.Fab")
			(effects
				(font
					(size 0.7 0.7)
					(thickness 0.15)
				)
				(justify right bottom)
			)
		)
		(property "Author" "Antmicro"
			(at 328.95 143.3 0)
			(layer "F.Fab")
			(hide yes)
			(effects
				(font
					(size 1 1)
					(thickness 0.15)
				)
			)
		)
		(property "Dielectric" ""
			(at 328.95 143.3 0)
			(layer "F.Fab")
			(hide yes)
			(effects
				(font
					(size 1 1)
					(thickness 0.15)
				)
			)
		)
		(property "License" "Apache-2.0"
			(at 328.95 143.3 0)
			(layer "F.Fab")
			(hide yes)
			(effects
				(font
					(size 1 1)
					(thickness 0.15)
				)
			)
		)
		(property "MPN" "GRM155R61A475MEAAD"
			(at 328.95 143.3 0)
			(layer "F.Fab")
			(hide yes)
			(effects
				(font
					(size 1 1)
					(thickness 0.15)
				)
			)
		)
		(property "Manufacturer" "Murata"
			(at 328.95 143.3 0)
			(layer "F.Fab")
			(hide yes)
			(effects
				(font
					(size 1 1)
					(thickness 0.15)
				)
			)
		)
		(property "Val" "4u7"
			(at 328.95 143.3 0)
			(layer "F.Fab")
			(hide yes)
			(effects
				(font
					(size 1 1)
					(thickness 0.15)
				)
			)
		)
		(property "Voltage" ""
			(at 328.95 143.3 0)
			(layer "F.Fab")
			(hide yes)
			(effects
				(font
					(size 1 1)
					(thickness 0.15)
				)
			)
		)
		(sheetname "Power supply")
		(sheetfile "power_supply.kicad_sch")
		(attr smd)
		(fp_rect
			(start -0.9659 -0.481258)
			(end 0.9649 0.458742)
			(stroke
				(width 0.05)
				(type solid)
			)
			(fill no)
			(layer "F.CrtYd")
		)
		(fp_line
			(start 0.499 0.248)
			(end -0.499 0.248)
			(stroke
				(width 0.15)
				(type solid)
			)
			(layer "F.Fab")
		)
		(fp_line
			(start 0.499 -0.25)
			(end 0.499 0.248)
			(stroke
				(width 0.15)
				(type solid)
			)
			(layer "F.Fab")
		)
		(fp_line
			(start -0.499 0.248)
			(end -0.499 -0.25)
			(stroke
				(width 0.15)
				(type solid)
			)
			(layer "F.Fab")
		)
		(fp_line
			(start -0.499 -0.25)
			(end 0.499 -0.25)
			(stroke
				(width 0.15)
				(type solid)
			)
			(layer "F.Fab")
		)
		(pad "1" smd roundrect
			(at -0.484 0 180)
			(size 0.59 0.64)
			(layers "F.Cu" "F.Mask" "F.Paste")
			(roundrect_rratio 0.25)
			(net 14 "GND")
			(pintype "passive")
		)
		(pad "2" smd roundrect
			(at 0.484 0 180)
			(size 0.59 0.64)
			(layers "F.Cu" "F.Mask" "F.Paste")
			(roundrect_rratio 0.25)
			(net 11 "/Power supply/VOUT")
			(pintype "passive")
		)
	)
	(footprint "antmicro-footprints:C_0603_1608Metric"
		(layer "F.Cu")
		(at 111.875 69.825 -90)
		(descr "Capacitor SMD 0603")
		(tags "capacitor 0603")
		(property "Reference" "C18"
			(at -2.025 -2.125 90)
			(unlocked yes)
			(layer "F.SilkS")
			(effects
				(font
					(size 0.7 0.7)
					(thickness 0.15)
				)
				(justify right bottom)
			)
		)
		(property "Value" "C_22u_0603"
			(at -1.42757 1.770288 90)
			(layer "F.Fab")
			(effects
				(font
					(size 0.7 0.7)
					(thickness 0.15)
				)
				(justify right bottom)
			)
		)
		(property "Author" "Antmicro"
			(at 42.05 181.7 0)
			(layer "F.Fab")
			(hide yes)
			(effects
				(font
					(size 1 1)
					(thickness 0.15)
				)
			)
		)
		(property "Dielectric" ""
			(at 42.05 181.7 0)
			(layer "F.Fab")
			(hide yes)
			(effects
				(font
					(size 1 1)
					(thickness 0.15)
				)
			)
		)
		(property "License" "Apache-2.0"
			(at 42.05 181.7 0)
			(layer "F.Fab")
			(hide yes)
			(effects
				(font
					(size 1 1)
					(thickness 0.15)
				)
			)
		)
		(property "MPN" "GRM188R60J226MEA0D"
			(at 42.05 181.7 0)
			(layer "F.Fab")
			(hide yes)
			(effects
				(font
					(size 1 1)
					(thickness 0.15)
				)
			)
		)
		(property "Manufacturer" "Murata"
			(at 42.05 181.7 0)
			(layer "F.Fab")
			(hide yes)
			(effects
				(font
					(size 1 1)
					(thickness 0.15)
				)
			)
		)
		(property "Val" "22u"
			(at 42.05 181.7 0)
			(layer "F.Fab")
			(hide yes)
			(effects
				(font
					(size 1 1)
					(thickness 0.15)
				)
			)
		)
		(property "Voltage" ""
			(at 42.05 181.7 0)
			(layer "F.Fab")
			(hide yes)
			(effects
				(font
					(size 1 1)
					(thickness 0.15)
				)
			)
		)
		(sheetname "Power supply")
		(sheetfile "power_supply.kicad_sch")
		(attr smd)
		(fp_line
			(start -0.3 0.3)
			(end 0.3 0.3)
			(stroke
				(width 0.15)
				(type solid)
			)
			(layer "F.SilkS")
		)
		(fp_line
			(start -0.3 -0.3)
			(end 0.3 -0.3)
			(stroke
				(width 0.15)
				(type solid)
			)
			(layer "F.SilkS")
		)
		(fp_rect
			(start -1.24 -0.7)
			(end 1.24 0.7)
			(stroke
				(width 0.05)
				(type solid)
			)
			(fill no)
			(layer "F.CrtYd")
		)
		(fp_rect
			(start -0.8 -0.4)
			(end 0.8 0.4)
			(stroke
				(width 0.15)
				(type solid)
			)
			(fill no)
			(layer "F.Fab")
		)
		(pad "1" smd roundrect
			(at -0.7 0 270)
			(size 0.6 0.8)
			(layers "F.Cu" "F.Mask" "F.Paste")
			(roundrect_rratio 0.2)
			(net 14 "GND")
			(pintype "passive")
		)
		(pad "2" smd roundrect
			(at 0.7 0 270)
			(size 0.6 0.8)
			(layers "F.Cu" "F.Mask" "F.Paste")
			(roundrect_rratio 0.2)
			(net 9 "/Power supply/VOUT3")
			(pintype "passive")
		)
	)
)
